(kicad_pcb
	(version 20260206)
	(generator "pcbnew")
	(generator_version "10.0")
	(general
		(thickness 1.6)
		(legacy_teardrops no)
	)
	(paper "A4")
	(title_block
		(title "04192023_DAF0TMB3IC0_F0TG_MB_C_brd_V02_OCP.brd")
		(comment 1 "Grand Teton / footprints 6802-6810 of 8354")
	)
	(layers
		(0 "F.Cu" signal "TOP")
		(4 "In1.Cu" signal "GND")
		(6 "In2.Cu" signal "IN1")
		(8 "In3.Cu" signal "GND1")
		(10 "In4.Cu" signal "IN2")
		(12 "In5.Cu" signal "GND2")
		(14 "In6.Cu" signal "IN3")
		(16 "In7.Cu" signal "GND3")
		(18 "In8.Cu" signal "VCC")
		(20 "In9.Cu" signal "VCC1")
		(22 "In10.Cu" signal "GND4")
		(24 "In11.Cu" signal "IN4")
		(26 "In12.Cu" signal "GND5")
		(28 "In13.Cu" signal "IN5")
		(30 "In14.Cu" signal "GND6")
		(32 "In15.Cu" signal "IN6")
		(34 "In16.Cu" signal "GND7")
		(2 "B.Cu" signal "BOTTOM")
		(9 "F.Adhes" user "F.Adhesive")
		(11 "B.Adhes" user "B.Adhesive")
		(13 "F.Paste" user "Package Geometry/Pastemask Top")
		(15 "B.Paste" user "Package Geometry/Pastemask Bottom")
		(5 "F.SilkS" user "Ref Des/Silkscreen Top")
		(7 "B.SilkS" user "Ref Des/Silkscreen Bottom")
		(1 "F.Mask" user "Board Geometry/Soldermask Top")
		(3 "B.Mask" user "Board Geometry/Soldermask Bottom")
		(17 "Dwgs.User" user "User.Drawings")
		(19 "Cmts.User" user "User.Comments")
		(21 "Eco1.User" user "User.Eco1")
		(23 "Eco2.User" user "User.Eco2")
		(25 "Edge.Cuts" user "Board Geometry/Outline")
		(27 "Margin" user)
		(31 "F.CrtYd" user "Package Geometry/Place Bound Top")
		(29 "B.CrtYd" user "Package Geometry/Place Bound Bottom")
		(35 "F.Fab" user "Ref Des/Assembly Top")
		(33 "B.Fab" user "Ref Des/Assembly Bottom")
	)
	(footprint ""
		(layer "B.Cu")
		(at 412.222442 -416.899344 90)
		(property "Reference" "C6624"
			(at 0 0 90)
			(layer "B.SilkS")
			(hide yes)
			(effects
				(font
					(size 1.27 1.27)
				)
				(justify mirror)
			)
		)
		(property "Value" ""
			(at 0 0 90)
			(layer "B.Fab")
			(effects
				(font
					(size 1.27 1.27)
				)
				(justify mirror)
			)
		)
		(duplicate_pad_numbers_are_jumpers no)
		(fp_line
			(start 0.299974 -0.150114)
			(end -0.299974 -0.150114)
			(stroke
				(width 0.1)
				(type default)
			)
			(layer "B.Fab")
		)
		(fp_line
			(start -0.299974 -0.150114)
			(end -0.299974 0.150114)
			(stroke
				(width 0.1)
				(type default)
			)
			(layer "B.Fab")
		)
		(fp_line
			(start 0.299974 0.150114)
			(end 0.299974 -0.150114)
			(stroke
				(width 0.1)
				(type default)
			)
			(layer "B.Fab")
		)
		(fp_line
			(start -0.299974 0.150114)
			(end 0.299974 0.150114)
			(stroke
				(width 0.1)
				(type default)
			)
			(layer "B.Fab")
		)
		(pad "1" smd rect
			(at 0.2667 0 270)
			(size 0.3048 0.381)
			(layers "B.Cu" "B.Mask" "B.Paste")
			(net "P5E_CPU0_P3_TX_BUF_C_DN<13>")
		)
		(pad "2" smd rect
			(at -0.2667 0 270)
			(size 0.3048 0.381)
			(layers "B.Cu" "B.Mask" "B.Paste")
			(net "P5E_CPU0_P3_TX_BUF_DN<13>")
		)
	)
	(footprint ""
		(layer "B.Cu")
		(at 159.018986 -390.909302 90)
		(property "Reference" "C423"
			(at 0 0 90)
			(layer "B.SilkS")
			(hide yes)
			(effects
				(font
					(size 1.27 1.27)
				)
				(justify mirror)
			)
		)
		(property "Value" ""
			(at 0 0 90)
			(layer "B.Fab")
			(effects
				(font
					(size 1.27 1.27)
				)
				(justify mirror)
			)
		)
		(duplicate_pad_numbers_are_jumpers no)
		(fp_line
			(start 0.299974 -0.150114)
			(end -0.299974 -0.150114)
			(stroke
				(width 0.1)
				(type default)
			)
			(layer "B.Fab")
		)
		(fp_line
			(start -0.299974 -0.150114)
			(end -0.299974 0.150114)
			(stroke
				(width 0.1)
				(type default)
			)
			(layer "B.Fab")
		)
		(fp_line
			(start 0.299974 0.150114)
			(end 0.299974 -0.150114)
			(stroke
				(width 0.1)
				(type default)
			)
			(layer "B.Fab")
		)
		(fp_line
			(start -0.299974 0.150114)
			(end 0.299974 0.150114)
			(stroke
				(width 0.1)
				(type default)
			)
			(layer "B.Fab")
		)
		(pad "1" smd rect
			(at 0.2667 0 270)
			(size 0.3048 0.381)
			(layers "B.Cu" "B.Mask" "B.Paste")
			(net "P0V9_CPU1_RT_2D")
		)
		(pad "2" smd rect
			(at -0.2667 0 270)
			(size 0.3048 0.381)
			(layers "B.Cu" "B.Mask" "B.Paste")
			(net "GND")
		)
	)
	(footprint ""
		(layer "B.Cu")
		(at 348.818454 -266.00531)
		(property "Reference" "C2603"
			(at 0 0 0)
			(layer "B.SilkS")
			(hide yes)
			(effects
				(font
					(size 1.27 1.27)
				)
				(justify mirror)
			)
		)
		(property "Value" ""
			(at 0 0 0)
			(layer "B.Fab")
			(effects
				(font
					(size 1.27 1.27)
				)
				(justify mirror)
			)
		)
		(duplicate_pad_numbers_are_jumpers no)
		(fp_line
			(start -0.7874 -0.4064)
			(end -0.7874 0.4064)
			(stroke
				(width 0.1524)
				(type default)
			)
			(layer "B.SilkS")
		)
		(fp_line
			(start -0.7874 0.4064)
			(end 0.7874 0.4064)
			(stroke
				(width 0.1524)
				(type default)
			)
			(layer "B.SilkS")
		)
		(fp_line
			(start 0.7874 -0.4064)
			(end -0.7874 -0.4064)
			(stroke
				(width 0.1524)
				(type default)
			)
			(layer "B.SilkS")
		)
		(fp_line
			(start 0.7874 0.4064)
			(end 0.7874 -0.4064)
			(stroke
				(width 0.1524)
				(type default)
			)
			(layer "B.SilkS")
		)
		(fp_line
			(start -0.67945 -0.3048)
			(end -0.67945 0.3048)
			(stroke
				(width 0.1)
				(type default)
			)
			(layer "B.Fab")
		)
		(fp_line
			(start -0.67945 0.3048)
			(end -0.120396 0.3048)
			(stroke
				(width 0.1)
				(type default)
			)
			(layer "B.Fab")
		)
		(fp_line
			(start -0.12065 -0.3048)
			(end -0.67945 -0.3048)
			(stroke
				(width 0.1)
				(type default)
			)
			(layer "B.Fab")
		)
		(fp_line
			(start -0.12065 -0.2794)
			(end -0.12065 -0.3048)
			(stroke
				(width 0.1)
				(type default)
			)
			(layer "B.Fab")
		)
		(fp_line
			(start -0.120396 0.2794)
			(end 0.12065 0.2794)
			(stroke
				(width 0.1)
				(type default)
			)
			(layer "B.Fab")
		)
		(fp_line
			(start -0.120396 0.3048)
			(end -0.120396 0.2794)
			(stroke
				(width 0.1)
				(type default)
			)
			(layer "B.Fab")
		)
		(fp_line
			(start 0.12065 -0.305054)
			(end 0.12065 -0.2794)
			(stroke
				(width 0.1)
				(type default)
			)
			(layer "B.Fab")
		)
		(fp_line
			(start 0.12065 -0.2794)
			(end -0.12065 -0.2794)
			(stroke
				(width 0.1)
				(type default)
			)
			(layer "B.Fab")
		)
		(fp_line
			(start 0.12065 0.2794)
			(end 0.12065 0.3048)
			(stroke
				(width 0.1)
				(type default)
			)
			(layer "B.Fab")
		)
		(fp_line
			(start 0.12065 0.3048)
			(end 0.67945 0.3048)
			(stroke
				(width 0.1)
				(type default)
			)
			(layer "B.Fab")
		)
		(fp_line
			(start 0.67945 -0.305054)
			(end 0.12065 -0.305054)
			(stroke
				(width 0.1)
				(type default)
			)
			(layer "B.Fab")
		)
		(fp_line
			(start 0.67945 0.3048)
			(end 0.67945 -0.305054)
			(stroke
				(width 0.1)
				(type default)
			)
			(layer "B.Fab")
		)
		(pad "1" smd circle
			(at 0.40005 0 180)
			(size 0 0)
			(layers "B.Cu" "B.Mask" "B.Paste")
			(net "PVDD11_S3_P0")
		)
		(pad "2" smd circle
			(at -0.40005 0 180)
			(size 0 0)
			(layers "B.Cu" "B.Mask" "B.Paste")
			(net "GND")
		)
	)
	(footprint ""
		(layer "B.Cu")
		(at 100.067872 -342.604598 -90)
		(property "Reference" "PR429"
			(at 0 0 90)
			(layer "B.SilkS")
			(hide yes)
			(effects
				(font
					(size 1.27 1.27)
				)
				(justify mirror)
			)
		)
		(property "Value" ""
			(at 0 0 90)
			(layer "B.Fab")
			(effects
				(font
					(size 1.27 1.27)
				)
				(justify mirror)
			)
		)
		(duplicate_pad_numbers_are_jumpers no)
		(fp_line
			(start -0.7874 0.4064)
			(end 0.7874 0.4064)
			(stroke
				(width 0.1524)
				(type default)
			)
			(layer "B.SilkS")
		)
		(fp_line
			(start 0.7874 0.4064)
			(end 0.7874 -0.4064)
			(stroke
				(width 0.1524)
				(type default)
			)
			(layer "B.SilkS")
		)
		(fp_line
			(start -0.7874 -0.4064)
			(end -0.7874 0.4064)
			(stroke
				(width 0.1524)
				(type default)
			)
			(layer "B.SilkS")
		)
		(fp_line
			(start 0.7874 -0.4064)
			(end -0.7874 -0.4064)
			(stroke
				(width 0.1524)
				(type default)
			)
			(layer "B.SilkS")
		)
		(fp_line
			(start -0.67945 0.3048)
			(end -0.120396 0.3048)
			(stroke
				(width 0.1)
				(type default)
			)
			(layer "B.Fab")
		)
		(fp_line
			(start -0.120396 0.3048)
			(end -0.120396 0.2794)
			(stroke
				(width 0.1)
				(type default)
			)
			(layer "B.Fab")
		)
		(fp_line
			(start 0.12065 0.3048)
			(end 0.67945 0.3048)
			(stroke
				(width 0.1)
				(type default)
			)
			(layer "B.Fab")
		)
		(fp_line
			(start 0.67945 0.3048)
			(end 0.67945 -0.305054)
			(stroke
				(width 0.1)
				(type default)
			)
			(layer "B.Fab")
		)
		(fp_line
			(start -0.120396 0.2794)
			(end 0.12065 0.2794)
			(stroke
				(width 0.1)
				(type default)
			)
			(layer "B.Fab")
		)
		(fp_line
			(start 0.12065 0.2794)
			(end 0.12065 0.3048)
			(stroke
				(width 0.1)
				(type default)
			)
			(layer "B.Fab")
		)
		(fp_line
			(start -0.12065 -0.2794)
			(end -0.12065 -0.3048)
			(stroke
				(width 0.1)
				(type default)
			)
			(layer "B.Fab")
		)
		(fp_line
			(start 0.12065 -0.2794)
			(end -0.12065 -0.2794)
			(stroke
				(width 0.1)
				(type default)
			)
			(layer "B.Fab")
		)
		(fp_line
			(start -0.67945 -0.3048)
			(end -0.67945 0.3048)
			(stroke
				(width 0.1)
				(type default)
			)
			(layer "B.Fab")
		)
		(fp_line
			(start -0.12065 -0.3048)
			(end -0.67945 -0.3048)
			(stroke
				(width 0.1)
				(type default)
			)
			(layer "B.Fab")
		)
		(fp_line
			(start 0.12065 -0.305054)
			(end 0.12065 -0.2794)
			(stroke
				(width 0.1)
				(type default)
			)
			(layer "B.Fab")
		)
		(fp_line
			(start 0.67945 -0.305054)
			(end 0.12065 -0.305054)
			(stroke
				(width 0.1)
				(type default)
			)
			(layer "B.Fab")
		)
		(pad "1" smd circle
			(at 0.40005 0 90)
			(size 0 0)
			(layers "B.Cu" "B.Mask" "B.Paste")
			(net "PVDDCR_CPU1_P1_VOS6")
		)
		(pad "2" smd circle
			(at -0.40005 0 90)
			(size 0 0)
			(layers "B.Cu" "B.Mask" "B.Paste")
			(net "PVDDCR_CPU1_P1")
		)
	)
	(footprint ""
		(layer "B.Cu")
		(at 234.644692 -422.849548 90)
		(property "Reference" "C65"
			(at 0 0 90)
			(layer "B.SilkS")
			(hide yes)
			(effects
				(font
					(size 1.27 1.27)
				)
				(justify mirror)
			)
		)
		(property "Value" ""
			(at 0 0 90)
			(layer "B.Fab")
			(effects
				(font
					(size 1.27 1.27)
				)
				(justify mirror)
			)
		)
		(duplicate_pad_numbers_are_jumpers no)
		(fp_line
			(start 0.7874 -0.4064)
			(end -0.7874 -0.4064)
			(stroke
				(width 0.1524)
				(type default)
			)
			(layer "B.SilkS")
		)
		(fp_line
			(start -0.7874 -0.4064)
			(end -0.7874 0.4064)
			(stroke
				(width 0.1524)
				(type default)
			)
			(layer "B.SilkS")
		)
		(fp_line
			(start 0.7874 0.4064)
			(end 0.7874 -0.4064)
			(stroke
				(width 0.1524)
				(type default)
			)
			(layer "B.SilkS")
		)
		(fp_line
			(start -0.7874 0.4064)
			(end 0.7874 0.4064)
			(stroke
				(width 0.1524)
				(type default)
			)
			(layer "B.SilkS")
		)
		(fp_line
			(start 0.67945 -0.305054)
			(end 0.12065 -0.305054)
			(stroke
				(width 0.1)
				(type default)
			)
			(layer "B.Fab")
		)
		(fp_line
			(start 0.12065 -0.305054)
			(end 0.12065 -0.2794)
			(stroke
				(width 0.1)
				(type default)
			)
			(layer "B.Fab")
		)
		(fp_line
			(start -0.12065 -0.3048)
			(end -0.67945 -0.3048)
			(stroke
				(width 0.1)
				(type default)
			)
			(layer "B.Fab")
		)
		(fp_line
			(start -0.67945 -0.3048)
			(end -0.67945 0.3048)
			(stroke
				(width 0.1)
				(type default)
			)
			(layer "B.Fab")
		)
		(fp_line
			(start 0.12065 -0.2794)
			(end -0.12065 -0.2794)
			(stroke
				(width 0.1)
				(type default)
			)
			(layer "B.Fab")
		)
		(fp_line
			(start -0.12065 -0.2794)
			(end -0.12065 -0.3048)
			(stroke
				(width 0.1)
				(type default)
			)
			(layer "B.Fab")
		)
		(fp_line
			(start 0.12065 0.2794)
			(end 0.12065 0.3048)
			(stroke
				(width 0.1)
				(type default)
			)
			(layer "B.Fab")
		)
		(fp_line
			(start -0.120396 0.2794)
			(end 0.12065 0.2794)
			(stroke
				(width 0.1)
				(type default)
			)
			(layer "B.Fab")
		)
		(fp_line
			(start 0.67945 0.3048)
			(end 0.67945 -0.305054)
			(stroke
				(width 0.1)
				(type default)
			)
			(layer "B.Fab")
		)
		(fp_line
			(start 0.12065 0.3048)
			(end 0.67945 0.3048)
			(stroke
				(width 0.1)
				(type default)
			)
			(layer "B.Fab")
		)
		(fp_line
			(start -0.120396 0.3048)
			(end -0.120396 0.2794)
			(stroke
				(width 0.1)
				(type default)
			)
			(layer "B.Fab")
		)
		(fp_line
			(start -0.67945 0.3048)
			(end -0.120396 0.3048)
			(stroke
				(width 0.1)
				(type default)
			)
			(layer "B.Fab")
		)
		(pad "1" smd circle
			(at 0.40005 0 270)
			(size 0 0)
			(layers "B.Cu" "B.Mask" "B.Paste")
			(net "HPDB_HSC_PWRGD_R")
		)
		(pad "2" smd circle
			(at -0.40005 0 270)
			(size 0 0)
			(layers "B.Cu" "B.Mask" "B.Paste")
			(net "GND")
		)
	)
	(footprint ""
		(layer "B.Cu")
		(at 184.061608 -126.833376 90)
		(property "Reference" "R1281"
			(at 0 0 90)
			(layer "B.SilkS")
			(hide yes)
			(effects
				(font
					(size 1.27 1.27)
				)
				(justify mirror)
			)
		)
		(property "Value" ""
			(at 0 0 90)
			(layer "B.Fab")
			(effects
				(font
					(size 1.27 1.27)
				)
				(justify mirror)
			)
		)
		(duplicate_pad_numbers_are_jumpers no)
		(fp_line
			(start 0.7874 -0.4064)
			(end -0.7874 -0.4064)
			(stroke
				(width 0.1524)
				(type default)
			)
			(layer "B.SilkS")
		)
		(fp_line
			(start -0.7874 -0.4064)
			(end -0.7874 0.4064)
			(stroke
				(width 0.1524)
				(type default)
			)
			(layer "B.SilkS")
		)
		(fp_line
			(start 0.7874 0.4064)
			(end 0.7874 -0.4064)
			(stroke
				(width 0.1524)
				(type default)
			)
			(layer "B.SilkS")
		)
		(fp_line
			(start -0.7874 0.4064)
			(end 0.7874 0.4064)
			(stroke
				(width 0.1524)
				(type default)
			)
			(layer "B.SilkS")
		)
		(fp_line
			(start 0.67945 -0.305054)
			(end 0.12065 -0.305054)
			(stroke
				(width 0.1)
				(type default)
			)
			(layer "B.Fab")
		)
		(fp_line
			(start 0.12065 -0.305054)
			(end 0.12065 -0.2794)
			(stroke
				(width 0.1)
				(type default)
			)
			(layer "B.Fab")
		)
		(fp_line
			(start -0.12065 -0.3048)
			(end -0.67945 -0.3048)
			(stroke
				(width 0.1)
				(type default)
			)
			(layer "B.Fab")
		)
		(fp_line
			(start -0.67945 -0.3048)
			(end -0.67945 0.3048)
			(stroke
				(width 0.1)
				(type default)
			)
			(layer "B.Fab")
		)
		(fp_line
			(start 0.12065 -0.2794)
			(end -0.12065 -0.2794)
			(stroke
				(width 0.1)
				(type default)
			)
			(layer "B.Fab")
		)
		(fp_line
			(start -0.12065 -0.2794)
			(end -0.12065 -0.3048)
			(stroke
				(width 0.1)
				(type default)
			)
			(layer "B.Fab")
		)
		(fp_line
			(start 0.12065 0.2794)
			(end 0.12065 0.3048)
			(stroke
				(width 0.1)
				(type default)
			)
			(layer "B.Fab")
		)
		(fp_line
			(start -0.120396 0.2794)
			(end 0.12065 0.2794)
			(stroke
				(width 0.1)
				(type default)
			)
			(layer "B.Fab")
		)
		(fp_line
			(start 0.67945 0.3048)
			(end 0.67945 -0.305054)
			(stroke
				(width 0.1)
				(type default)
			)
			(layer "B.Fab")
		)
		(fp_line
			(start 0.12065 0.3048)
			(end 0.67945 0.3048)
			(stroke
				(width 0.1)
				(type default)
			)
			(layer "B.Fab")
		)
		(fp_line
			(start -0.120396 0.3048)
			(end -0.120396 0.2794)
			(stroke
				(width 0.1)
				(type default)
			)
			(layer "B.Fab")
		)
		(fp_line
			(start -0.67945 0.3048)
			(end -0.120396 0.3048)
			(stroke
				(width 0.1)
				(type default)
			)
			(layer "B.Fab")
		)
		(pad "1" smd circle
			(at 0.40005 0 270)
			(size 0 0)
			(layers "B.Cu" "B.Mask" "B.Paste")
			(net "FM_P0_PCC1_N")
		)
		(pad "2" smd circle
			(at -0.40005 0 270)
			(size 0 0)
			(layers "B.Cu" "B.Mask" "B.Paste")
			(net "FM_P0_PCC1_R_N")
		)
	)
	(footprint ""
		(layer "B.Cu")
		(at 390.51738 -396.150592 180)
		(property "Reference" "C1047"
			(at 0 0 0)
			(layer "B.SilkS")
			(hide yes)
			(effects
				(font
					(size 1.27 1.27)
				)
				(justify mirror)
			)
		)
		(property "Value" ""
			(at 0 0 0)
			(layer "B.Fab")
			(effects
				(font
					(size 1.27 1.27)
				)
				(justify mirror)
			)
		)
		(duplicate_pad_numbers_are_jumpers no)
		(fp_line
			(start 0.299974 0.150114)
			(end 0.299974 -0.150114)
			(stroke
				(width 0.1)
				(type default)
			)
			(layer "B.Fab")
		)
		(fp_line
			(start 0.299974 -0.150114)
			(end -0.299974 -0.150114)
			(stroke
				(width 0.1)
				(type default)
			)
			(layer "B.Fab")
		)
		(fp_line
			(start -0.299974 0.150114)
			(end 0.299974 0.150114)
			(stroke
				(width 0.1)
				(type default)
			)
			(layer "B.Fab")
		)
		(fp_line
			(start -0.299974 -0.150114)
			(end -0.299974 0.150114)
			(stroke
				(width 0.1)
				(type default)
			)
			(layer "B.Fab")
		)
		(pad "1" smd rect
			(at 0.2667 0)
			(size 0.3048 0.381)
			(layers "B.Cu" "B.Mask" "B.Paste")
			(net "P0V9_CPU0_RT3_2A")
		)
		(pad "2" smd rect
			(at -0.2667 0)
			(size 0.3048 0.381)
			(layers "B.Cu" "B.Mask" "B.Paste")
			(net "GND")
		)
	)
	(footprint ""
		(layer "B.Cu")
		(at 346.700856 -161.263076 -90)
		(property "Reference" "PC158_6"
			(at 0 0 90)
			(layer "B.SilkS")
			(hide yes)
			(effects
				(font
					(size 1.27 1.27)
				)
				(justify mirror)
			)
		)
		(property "Value" ""
			(at 0 0 90)
			(layer "B.Fab")
			(effects
				(font
					(size 1.27 1.27)
				)
				(justify mirror)
			)
		)
		(duplicate_pad_numbers_are_jumpers no)
		(fp_line
			(start -1.524 0.762)
			(end 1.524 0.762)
			(stroke
				(width 0.1524)
				(type default)
			)
			(layer "B.SilkS")
		)
		(fp_line
			(start 1.524 0.762)
			(end 1.524 -0.762)
			(stroke
				(width 0.1524)
				(type default)
			)
			(layer "B.SilkS")
		)
		(fp_line
			(start -1.524 -0.762)
			(end -1.524 0.762)
			(stroke
				(width 0.1524)
				(type default)
			)
			(layer "B.SilkS")
		)
		(fp_line
			(start 1.524 -0.762)
			(end -1.524 -0.762)
			(stroke
				(width 0.1524)
				(type default)
			)
			(layer "B.SilkS")
		)
		(fp_line
			(start -1.1049 0.724916)
			(end -1.1049 -0.724916)
			(stroke
				(width 0.1)
				(type default)
			)
			(layer "B.Fab")
		)
		(fp_line
			(start 1.1049 0.724916)
			(end -1.1049 0.724916)
			(stroke
				(width 0.1)
				(type default)
			)
			(layer "B.Fab")
		)
		(fp_line
			(start -1.1049 -0.724916)
			(end 1.1049 -0.724916)
			(stroke
				(width 0.1)
				(type default)
			)
			(layer "B.Fab")
		)
		(fp_line
			(start 1.1049 -0.724916)
			(end 1.1049 0.724916)
			(stroke
				(width 0.1)
				(type default)
			)
			(layer "B.Fab")
		)
		(pad "1" smd rect
			(at 0.889 0 270)
			(size 1.016 1.27)
			(layers "B.Cu" "B.Mask" "B.Paste")
			(net "SW_P12V_AUX_PVDDCR_CPU0_P0_FLT")
		)
		(pad "2" smd rect
			(at -0.889 0 270)
			(size 1.016 1.27)
			(layers "B.Cu" "B.Mask" "B.Paste")
			(net "GND")
		)
	)
	(footprint ""
		(layer "B.Cu")
		(at 110.365794 -384.66268 180)
		(property "Reference" "R921"
			(at 0 0 0)
			(layer "B.SilkS")
			(hide yes)
			(effects
				(font
					(size 1.27 1.27)
				)
				(justify mirror)
			)
		)
		(property "Value" ""
			(at 0 0 0)
			(layer "B.Fab")
			(effects
				(font
					(size 1.27 1.27)
				)
				(justify mirror)
			)
		)
		(duplicate_pad_numbers_are_jumpers no)
		(fp_line
			(start 0.32512 0.175006)
			(end 0.32512 -0.175006)
			(stroke
				(width 0.1)
				(type default)
			)
			(layer "B.Fab")
		)
		(fp_line
			(start 0.32512 -0.175006)
			(end -0.32512 -0.175006)
			(stroke
				(width 0.1)
				(type default)
			)
			(layer "B.Fab")
		)
		(fp_line
			(start -0.32512 0.175006)
			(end 0.32512 0.175006)
			(stroke
				(width 0.1)
				(type default)
			)
			(layer "B.Fab")
		)
		(fp_line
			(start -0.32512 -0.175006)
			(end -0.32512 0.175006)
			(stroke
				(width 0.1)
				(type default)
			)
			(layer "B.Fab")
		)
		(pad "1" smd rect
			(at 0.2667 0)
			(size 0.3048 0.381)
			(layers "B.Cu" "B.Mask" "B.Paste")
			(net "TEST1_RT_CPU1_P3")
		)
		(pad "2" smd rect
			(at -0.2667 0 180)
			(size 0.3048 0.381)
			(layers "B.Cu" "B.Mask" "B.Paste")
			(net "GND")
		)
	)
)
